G04*
G04 #@! TF.GenerationSoftware,Altium Limited,Altium Designer,23.6.0 (18)*
G04*
G04 Layer_Color=8388736*
%FSLAX44Y44*%
%MOMM*%
G71*
G04*
G04 #@! TF.SameCoordinates,59133E90-4310-4D8A-9E2C-91A8D2F69FBB*
G04*
G04*
G04 #@! TF.FilePolarity,Negative*
G04*
G01*
G75*
%ADD14R,0.5153X0.4725*%
%ADD15R,0.5000X0.6000*%
%ADD17R,0.6153X0.5725*%
%ADD18R,1.7062X1.1546*%
%ADD22R,0.8000X0.8000*%
%ADD24R,4.9000X1.1000*%
%ADD27R,0.5725X0.6153*%
%ADD30R,0.3627X0.4541*%
%ADD31R,0.8500X0.6500*%
%ADD32R,0.6000X0.5000*%
%ADD33R,0.5811X0.4725*%
%ADD34R,0.4725X0.5811*%
%ADD37R,1.1546X1.7062*%
%ADD38R,0.7000X0.6500*%
%ADD39R,1.2000X1.2000*%
%ADD40R,0.9000X1.6000*%
%ADD41R,1.6000X0.9000*%
%ADD42R,1.0000X0.9000*%
G04:AMPARAMS|DCode=43|XSize=0.5mm|YSize=0.95mm|CornerRadius=0.1mm|HoleSize=0mm|Usage=FLASHONLY|Rotation=180.000|XOffset=0mm|YOffset=0mm|HoleType=Round|Shape=RoundedRectangle|*
%AMROUNDEDRECTD43*
21,1,0.5000,0.7500,0,0,180.0*
21,1,0.3000,0.9500,0,0,180.0*
1,1,0.2000,-0.1500,0.3750*
1,1,0.2000,0.1500,0.3750*
1,1,0.2000,0.1500,-0.3750*
1,1,0.2000,-0.1500,-0.3750*
%
%ADD43ROUNDEDRECTD43*%
G04:AMPARAMS|DCode=44|XSize=0.4mm|YSize=0.9mm|CornerRadius=0.0995mm|HoleSize=0mm|Usage=FLASHONLY|Rotation=0.000|XOffset=0mm|YOffset=0mm|HoleType=Round|Shape=RoundedRectangle|*
%AMROUNDEDRECTD44*
21,1,0.4000,0.7010,0,0,0.0*
21,1,0.2010,0.9000,0,0,0.0*
1,1,0.1990,0.1005,-0.3505*
1,1,0.1990,-0.1005,-0.3505*
1,1,0.1990,-0.1005,0.3505*
1,1,0.1990,0.1005,0.3505*
%
%ADD44ROUNDEDRECTD44*%
%ADD45R,1.1500X2.3000*%
%ADD46R,1.1000X1.1500*%
%ADD47R,0.6500X0.7000*%
%ADD48R,0.4500X1.5500*%
%ADD49C,0.5064*%
%ADD50C,5.6000*%
D14*
X106214Y155000D02*
D03*
X113786D02*
D03*
X67786Y127000D02*
D03*
X60214D02*
D03*
X135786Y145000D02*
D03*
X128214D02*
D03*
X135786Y155000D02*
D03*
X128214D02*
D03*
X84237Y155226D02*
D03*
X91808D02*
D03*
D15*
X77000Y373250D02*
D03*
X87000D02*
D03*
X165000Y97000D02*
D03*
X155000D02*
D03*
X22000Y131000D02*
D03*
X32000D02*
D03*
X59000Y140000D02*
D03*
X69000D02*
D03*
D17*
X162593Y364779D02*
D03*
X171164D02*
D03*
X22714Y410000D02*
D03*
X31286D02*
D03*
D18*
X202000Y51242D02*
D03*
Y76758D02*
D03*
D22*
X191500Y97000D02*
D03*
X176500D02*
D03*
X32878Y117328D02*
D03*
X17879D02*
D03*
D24*
X120000Y348000D02*
D03*
Y376000D02*
D03*
D27*
X171000Y353286D02*
D03*
Y344714D02*
D03*
X40000Y345714D02*
D03*
Y354286D02*
D03*
D30*
X151962Y357973D02*
D03*
Y364059D02*
D03*
D31*
X171295Y375639D02*
D03*
X183795D02*
D03*
D32*
X11000Y339000D02*
D03*
Y349000D02*
D03*
X26000Y339000D02*
D03*
Y349000D02*
D03*
D33*
X66655Y373238D02*
D03*
X59345D02*
D03*
D34*
X54000Y352345D02*
D03*
Y359655D02*
D03*
D37*
X12242Y68000D02*
D03*
X37758D02*
D03*
D38*
X83250Y101000D02*
D03*
X74750D02*
D03*
X83250Y112000D02*
D03*
X74750D02*
D03*
D39*
X184000Y194600D02*
D03*
X163000Y194600D02*
D03*
X142000D02*
D03*
X121000D02*
D03*
X100000D02*
D03*
X79000D02*
D03*
X58000D02*
D03*
X37000D02*
D03*
X184000Y215600D02*
D03*
X163000Y215600D02*
D03*
X142000D02*
D03*
X121000D02*
D03*
X100000D02*
D03*
X79000D02*
D03*
X58000D02*
D03*
X37000D02*
D03*
X184000Y236600D02*
D03*
X163000Y236600D02*
D03*
X142000D02*
D03*
X121000D02*
D03*
X100000D02*
D03*
X79000D02*
D03*
X58000D02*
D03*
X37000D02*
D03*
X184000Y257600D02*
D03*
X163000Y257600D02*
D03*
X142000D02*
D03*
X121000D02*
D03*
X100000D02*
D03*
X79000D02*
D03*
X58000D02*
D03*
X37000D02*
D03*
X184000Y278600D02*
D03*
X163000Y278600D02*
D03*
X142000D02*
D03*
X121000D02*
D03*
X100000D02*
D03*
X79000D02*
D03*
X58000D02*
D03*
X37000D02*
D03*
X184000Y299600D02*
D03*
X163000Y299600D02*
D03*
X142000D02*
D03*
X121000D02*
D03*
X100000D02*
D03*
X79000D02*
D03*
X58000D02*
D03*
X37000D02*
D03*
D40*
X182000Y172600D02*
D03*
X171000D02*
D03*
X160000D02*
D03*
X149000D02*
D03*
X138000D02*
D03*
X127000D02*
D03*
X116000D02*
D03*
X105000D02*
D03*
X94000D02*
D03*
X83000D02*
D03*
X72000D02*
D03*
X61000D02*
D03*
X50000D02*
D03*
X39000D02*
D03*
Y321600D02*
D03*
X50000D02*
D03*
X61000D02*
D03*
X72000D02*
D03*
X83000D02*
D03*
X94000D02*
D03*
X105000D02*
D03*
X116000D02*
D03*
X127000D02*
D03*
X138000D02*
D03*
X149000D02*
D03*
X160000D02*
D03*
X171000D02*
D03*
X182000D02*
D03*
D41*
X11000Y181100D02*
D03*
Y192100D02*
D03*
Y203100D02*
D03*
Y214100D02*
D03*
Y225100D02*
D03*
Y236100D02*
D03*
Y247100D02*
D03*
Y258100D02*
D03*
Y269100D02*
D03*
Y280100D02*
D03*
Y291100D02*
D03*
Y302100D02*
D03*
Y313100D02*
D03*
X210000D02*
D03*
Y258100D02*
D03*
Y269100D02*
D03*
Y302100D02*
D03*
Y291100D02*
D03*
Y280100D02*
D03*
Y247100D02*
D03*
Y236100D02*
D03*
Y225100D02*
D03*
Y214100D02*
D03*
Y203100D02*
D03*
Y192100D02*
D03*
Y181100D02*
D03*
D42*
X66000Y361500D02*
D03*
Y342500D02*
D03*
X86000Y352000D02*
D03*
D43*
X44500Y385480D02*
D03*
X51000D02*
D03*
X57500D02*
D03*
Y407980D02*
D03*
X44500D02*
D03*
D44*
X13500Y360000D02*
D03*
X18500D02*
D03*
X23500D02*
D03*
X28500D02*
D03*
X13500Y392000D02*
D03*
X18500D02*
D03*
X23500D02*
D03*
X28500D02*
D03*
D45*
X156554Y404624D02*
D03*
X186054D02*
D03*
D46*
X171304Y389374D02*
D03*
D47*
X114000Y73750D02*
D03*
Y82250D02*
D03*
X104000Y73750D02*
D03*
Y82250D02*
D03*
X69000Y85250D02*
D03*
Y76750D02*
D03*
X81000Y85250D02*
D03*
Y76750D02*
D03*
D48*
X17500Y12750D02*
D03*
X22500D02*
D03*
X27500D02*
D03*
X32500D02*
D03*
X37500D02*
D03*
X42500D02*
D03*
X47500D02*
D03*
X52500D02*
D03*
X57500D02*
D03*
X62500D02*
D03*
X67500D02*
D03*
X72500D02*
D03*
X77500D02*
D03*
X82500D02*
D03*
X87500D02*
D03*
X92500D02*
D03*
X97500D02*
D03*
X102500D02*
D03*
X107500D02*
D03*
X112500D02*
D03*
X117500D02*
D03*
X122500D02*
D03*
X127500D02*
D03*
X132500D02*
D03*
X137500D02*
D03*
X142500D02*
D03*
X147500D02*
D03*
X152500D02*
D03*
X187500D02*
D03*
X192500D02*
D03*
X197500D02*
D03*
X202500D02*
D03*
X182500D02*
D03*
X177500D02*
D03*
D49*
X211156Y38620D02*
D03*
X126000Y100000D02*
D03*
X104000Y107000D02*
D03*
X209830Y407680D02*
D03*
Y397520D02*
D03*
Y387360D02*
D03*
Y377200D02*
D03*
Y367040D02*
D03*
Y356880D02*
D03*
Y346720D02*
D03*
Y336560D02*
D03*
Y326400D02*
D03*
X199670Y407680D02*
D03*
Y397520D02*
D03*
Y387360D02*
D03*
Y377200D02*
D03*
Y367040D02*
D03*
Y356880D02*
D03*
Y346720D02*
D03*
Y336560D02*
D03*
Y326400D02*
D03*
X189510Y387360D02*
D03*
Y367040D02*
D03*
Y356880D02*
D03*
Y346720D02*
D03*
Y336560D02*
D03*
Y326400D02*
D03*
X179350Y367040D02*
D03*
Y356880D02*
D03*
Y346720D02*
D03*
Y336560D02*
D03*
X169190Y407680D02*
D03*
X159030Y387360D02*
D03*
Y377200D02*
D03*
Y356880D02*
D03*
Y346720D02*
D03*
Y336560D02*
D03*
X148870Y387360D02*
D03*
Y346720D02*
D03*
X138710Y397520D02*
D03*
Y387360D02*
D03*
X128550D02*
D03*
X118390D02*
D03*
X98070D02*
D03*
X87910Y306080D02*
D03*
X77750Y407680D02*
D03*
Y387360D02*
D03*
Y356880D02*
D03*
X67590Y397520D02*
D03*
Y306080D02*
D03*
Y295920D02*
D03*
Y285760D02*
D03*
Y275600D02*
D03*
X190545Y43935D02*
D03*
X115000Y146000D02*
D03*
X106178Y147000D02*
D03*
X115000Y139000D02*
D03*
X168000Y131000D02*
D03*
X204000Y111000D02*
D03*
X166000Y112000D02*
D03*
X201000Y120000D02*
D03*
X167000D02*
D03*
X154373Y105997D02*
D03*
X210000Y181100D02*
D03*
Y192100D02*
D03*
X76611Y127172D02*
D03*
X52102Y139442D02*
D03*
X53051Y126729D02*
D03*
X41792Y117242D02*
D03*
X39452Y130651D02*
D03*
X12000Y65000D02*
D03*
Y74000D02*
D03*
X37758Y73000D02*
D03*
X37000Y64000D02*
D03*
X206000Y52000D02*
D03*
X197000D02*
D03*
X207000Y77000D02*
D03*
X198000D02*
D03*
X204000Y40054D02*
D03*
X191000Y37000D02*
D03*
X90162Y85574D02*
D03*
X80512Y67616D02*
D03*
X106948Y62472D02*
D03*
X93057Y101595D02*
D03*
X94793Y112219D02*
D03*
X65988Y100369D02*
D03*
X66000Y112000D02*
D03*
X145027Y145180D02*
D03*
X128214Y138000D02*
D03*
X181826Y161442D02*
D03*
X148849Y161221D02*
D03*
X138262Y162104D02*
D03*
X83228D02*
D03*
X83000Y146000D02*
D03*
X91831Y146884D02*
D03*
X37000Y194600D02*
D03*
X58000D02*
D03*
X79000D02*
D03*
X100000Y194000D02*
D03*
X121000Y194600D02*
D03*
X142000D02*
D03*
X163000D02*
D03*
X184000Y194600D02*
D03*
X37000Y215600D02*
D03*
X58000D02*
D03*
X79000D02*
D03*
X100000Y215000D02*
D03*
X121000Y215600D02*
D03*
X142000D02*
D03*
X163000D02*
D03*
X184000Y215600D02*
D03*
X37000Y236600D02*
D03*
X58000D02*
D03*
X79000D02*
D03*
X100000Y236000D02*
D03*
X121000Y236600D02*
D03*
X142000D02*
D03*
X163000D02*
D03*
X184000Y236600D02*
D03*
X37000Y257000D02*
D03*
X58000D02*
D03*
X79000D02*
D03*
X100000Y256400D02*
D03*
X121000Y257000D02*
D03*
X142000D02*
D03*
X163000D02*
D03*
X184000Y257000D02*
D03*
X37000Y278600D02*
D03*
X58000D02*
D03*
X79000D02*
D03*
X100000Y278000D02*
D03*
X121000Y278600D02*
D03*
X142000D02*
D03*
X163000D02*
D03*
X184000Y278600D02*
D03*
Y299600D02*
D03*
X163000Y299600D02*
D03*
X142000D02*
D03*
X121000D02*
D03*
X100000Y299000D02*
D03*
X79000Y299600D02*
D03*
X58000D02*
D03*
X37000D02*
D03*
X210000Y203100D02*
D03*
Y214100D02*
D03*
Y236100D02*
D03*
Y258100D02*
D03*
Y302100D02*
D03*
Y313100D02*
D03*
X149024Y334175D02*
D03*
X137823Y333314D02*
D03*
X126909Y334032D02*
D03*
X17430Y401507D02*
D03*
X68713Y403287D02*
D03*
X14291Y409878D02*
D03*
X11151Y401828D02*
D03*
X53974Y359649D02*
D03*
X23386Y401023D02*
D03*
X51000Y371000D02*
D03*
X50396Y377474D02*
D03*
X31414Y403184D02*
D03*
X11000Y339000D02*
D03*
X18519Y343994D02*
D03*
X26000Y349000D02*
D03*
X11000D02*
D03*
X49915Y341352D02*
D03*
X39824Y361855D02*
D03*
X63000Y38000D02*
D03*
X176000Y44000D02*
D03*
X111000Y35000D02*
D03*
X152000Y36000D02*
D03*
X137000D02*
D03*
X123000Y35000D02*
D03*
X93000Y34000D02*
D03*
X33000Y31000D02*
D03*
Y38000D02*
D03*
X32880Y45166D02*
D03*
X33000Y51645D02*
D03*
X15000Y50312D02*
D03*
X12791Y42000D02*
D03*
X6395Y41971D02*
D03*
X6826Y50312D02*
D03*
D50*
X110000Y420000D02*
D03*
M02*
